# T6G (Grand Teton) — schematic netlist excerpt (pin names and nets, part order shuffled) for the footprints in the layout excerpt that follows; sources: Cadence DE-HDL packaged netlist, KiCad conversion of 04192023_DAF0TMB3IC0_F0TG_MB_C_brd_V02_OCP.brd

R1247  Q_RES  0 5% EMPTY  pkg 0402LF  page 258 : A = PVDD18_S5_P0_ADC ; B = PVDD18_S5_P0_ADC_MAM
PC7001  Q_CAP  22UF 16V 20% X6S  pkg C0805  page 222 : A = SW_P12V_AUX_PVDDIO_P1_FLT ; B = GND
R6810  Q_RES  0 5% CHIP  pkg 0201LF  page 184 : A = SMB_RT_CPU1_P0_R_SDA ; B = SMB_RT_CPU1_P0_SDA

(kicad_pcb
	(version 20260206)
	(generator "pcbnew")
	(generator_version "10.0")
	(general
		(thickness 1.6)
		(legacy_teardrops no)
	)
	(paper "A4")
	(title_block
		(title "04192023_DAF0TMB3IC0_F0TG_MB_C_brd_V02_OCP.brd")
		(comment 1 "Grand Teton / footprints 5218-5220 of 8354")
	)
	(layers
		(0 "F.Cu" signal "TOP")
		(4 "In1.Cu" signal "GND")
		(6 "In2.Cu" signal "IN1")
		(8 "In3.Cu" signal "GND1")
		(10 "In4.Cu" signal "IN2")
		(12 "In5.Cu" signal "GND2")
		(14 "In6.Cu" signal "IN3")
		(16 "In7.Cu" signal "GND3")
		(18 "In8.Cu" signal "VCC")
		(20 "In9.Cu" signal "VCC1")
		(22 "In10.Cu" signal "GND4")
		(24 "In11.Cu" signal "IN4")
		(26 "In12.Cu" signal "GND5")
		(28 "In13.Cu" signal "IN5")
		(30 "In14.Cu" signal "GND6")
		(32 "In15.Cu" signal "IN6")
		(34 "In16.Cu" signal "GND7")
		(2 "B.Cu" signal "BOTTOM")
		(9 "F.Adhes" user "F.Adhesive")
		(11 "B.Adhes" user "B.Adhesive")
		(13 "F.Paste" user "Package Geometry/Pastemask Top")
		(15 "B.Paste" user "Package Geometry/Pastemask Bottom")
		(5 "F.SilkS" user "Ref Des/Silkscreen Top")
		(7 "B.SilkS" user "Ref Des/Silkscreen Bottom")
		(1 "F.Mask" user "Board Geometry/Soldermask Top")
		(3 "B.Mask" user "Board Geometry/Soldermask Bottom")
		(17 "Dwgs.User" user "User.Drawings")
		(19 "Cmts.User" user "User.Comments")
		(21 "Eco1.User" user "User.Eco1")
		(23 "Eco2.User" user "User.Eco2")
		(25 "Edge.Cuts" user "Board Geometry/Outline")
		(27 "Margin" user)
		(31 "F.CrtYd" user "Package Geometry/Place Bound Top")
		(29 "B.CrtYd" user "Package Geometry/Place Bound Bottom")
		(35 "F.Fab" user "Ref Des/Assembly Top")
		(33 "B.Fab" user "Ref Des/Assembly Bottom")
	)
	(footprint ""
		(layer "B.Cu")
		(at 231.834182 -328.25182 180)
		(property "Reference" "R1247"
			(at 0 0 0)
			(layer "B.SilkS")
			(hide yes)
			(effects
				(font
					(size 1.27 1.27)
				)
				(justify mirror)
			)
		)
		(property "Value" ""
			(at 0 0 0)
			(layer "B.Fab")
			(effects
				(font
					(size 1.27 1.27)
				)
				(justify mirror)
			)
		)
		(duplicate_pad_numbers_are_jumpers no)
		(fp_line
			(start 0.7874 0.4064)
			(end 0.7874 -0.4064)
			(stroke
				(width 0.1524)
				(type default)
			)
			(layer "B.SilkS")
		)
		(fp_line
			(start 0.7874 -0.4064)
			(end -0.7874 -0.4064)
			(stroke
				(width 0.1524)
				(type default)
			)
			(layer "B.SilkS")
		)
		(fp_line
			(start -0.7874 0.4064)
			(end 0.7874 0.4064)
			(stroke
				(width 0.1524)
				(type default)
			)
			(layer "B.SilkS")
		)
		(fp_line
			(start -0.7874 -0.4064)
			(end -0.7874 0.4064)
			(stroke
				(width 0.1524)
				(type default)
			)
			(layer "B.SilkS")
		)
		(fp_line
			(start 0.67945 0.3048)
			(end 0.67945 -0.305054)
			(stroke
				(width 0.1)
				(type default)
			)
			(layer "B.Fab")
		)
		(fp_line
			(start 0.67945 -0.305054)
			(end 0.12065 -0.305054)
			(stroke
				(width 0.1)
				(type default)
			)
			(layer "B.Fab")
		)
		(fp_line
			(start 0.12065 0.3048)
			(end 0.67945 0.3048)
			(stroke
				(width 0.1)
				(type default)
			)
			(layer "B.Fab")
		)
		(fp_line
			(start 0.12065 0.2794)
			(end 0.12065 0.3048)
			(stroke
				(width 0.1)
				(type default)
			)
			(layer "B.Fab")
		)
		(fp_line
			(start 0.12065 -0.2794)
			(end -0.12065 -0.2794)
			(stroke
				(width 0.1)
				(type default)
			)
			(layer "B.Fab")
		)
		(fp_line
			(start 0.12065 -0.305054)
			(end 0.12065 -0.2794)
			(stroke
				(width 0.1)
				(type default)
			)
			(layer "B.Fab")
		)
		(fp_line
			(start -0.120396 0.3048)
			(end -0.120396 0.2794)
			(stroke
				(width 0.1)
				(type default)
			)
			(layer "B.Fab")
		)
		(fp_line
			(start -0.120396 0.2794)
			(end 0.12065 0.2794)
			(stroke
				(width 0.1)
				(type default)
			)
			(layer "B.Fab")
		)
		(fp_line
			(start -0.12065 -0.2794)
			(end -0.12065 -0.3048)
			(stroke
				(width 0.1)
				(type default)
			)
			(layer "B.Fab")
		)
		(fp_line
			(start -0.12065 -0.3048)
			(end -0.67945 -0.3048)
			(stroke
				(width 0.1)
				(type default)
			)
			(layer "B.Fab")
		)
		(fp_line
			(start -0.67945 0.3048)
			(end -0.120396 0.3048)
			(stroke
				(width 0.1)
				(type default)
			)
			(layer "B.Fab")
		)
		(fp_line
			(start -0.67945 -0.3048)
			(end -0.67945 0.3048)
			(stroke
				(width 0.1)
				(type default)
			)
			(layer "B.Fab")
		)
		(pad "1" smd rect
			(at 0.40005 0 180)
			(size 0.4572 0.508)
			(layers "B.Cu" "B.Mask" "B.Paste")
			(net "PVDD18_S5_P0_ADC")
		)
		(pad "2" smd rect
			(at -0.40005 0 180)
			(size 0.4572 0.508)
			(layers "B.Cu" "B.Mask" "B.Paste")
			(net "PVDD18_S5_P0_ADC_MAM")
		)
	)
	(footprint ""
		(layer "B.Cu")
		(at 217.678 -334.01 180)
		(property "Reference" "R6810"
			(at 0 0 0)
			(layer "B.SilkS")
			(hide yes)
			(effects
				(font
					(size 1.27 1.27)
				)
				(justify mirror)
			)
		)
		(property "Value" ""
			(at 0 0 0)
			(layer "B.Fab")
			(effects
				(font
					(size 1.27 1.27)
				)
				(justify mirror)
			)
		)
		(duplicate_pad_numbers_are_jumpers no)
		(fp_line
			(start 0.32512 0.175006)
			(end 0.32512 -0.175006)
			(stroke
				(width 0.1)
				(type default)
			)
			(layer "B.Fab")
		)
		(fp_line
			(start 0.32512 -0.175006)
			(end -0.32512 -0.175006)
			(stroke
				(width 0.1)
				(type default)
			)
			(layer "B.Fab")
		)
		(fp_line
			(start -0.32512 0.175006)
			(end 0.32512 0.175006)
			(stroke
				(width 0.1)
				(type default)
			)
			(layer "B.Fab")
		)
		(fp_line
			(start -0.32512 -0.175006)
			(end -0.32512 0.175006)
			(stroke
				(width 0.1)
				(type default)
			)
			(layer "B.Fab")
		)
		(pad "1" smd rect
			(at 0.2667 0)
			(size 0.3048 0.381)
			(layers "B.Cu" "B.Mask" "B.Paste")
			(net "SMB_RT_CPU1_P0_R_SDA")
		)
		(pad "2" smd rect
			(at -0.2667 0 180)
			(size 0.3048 0.381)
			(layers "B.Cu" "B.Mask" "B.Paste")
			(net "SMB_RT_CPU1_P0_SDA")
		)
	)
	(footprint ""
		(layer "B.Cu")
		(at 30.65526 -353.11334)
		(property "Reference" "PC7001"
			(at 0 0 0)
			(layer "B.SilkS")
			(hide yes)
			(effects
				(font
					(size 1.27 1.27)
				)
				(justify mirror)
			)
		)
		(property "Value" ""
			(at 0 0 0)
			(layer "B.Fab")
			(effects
				(font
					(size 1.27 1.27)
				)
				(justify mirror)
			)
		)
		(duplicate_pad_numbers_are_jumpers no)
		(fp_line
			(start -1.524 -0.762)
			(end -1.524 0.762)
			(stroke
				(width 0.1524)
				(type default)
			)
			(layer "B.SilkS")
		)
		(fp_line
			(start -1.524 0.762)
			(end 1.524 0.762)
			(stroke
				(width 0.1524)
				(type default)
			)
			(layer "B.SilkS")
		)
		(fp_line
			(start 1.524 -0.762)
			(end -1.524 -0.762)
			(stroke
				(width 0.1524)
				(type default)
			)
			(layer "B.SilkS")
		)
		(fp_line
			(start 1.524 0.762)
			(end 1.524 -0.762)
			(stroke
				(width 0.1524)
				(type default)
			)
			(layer "B.SilkS")
		)
		(fp_line
			(start -1.1049 -0.724916)
			(end 1.1049 -0.724916)
			(stroke
				(width 0.1)
				(type default)
			)
			(layer "B.Fab")
		)
		(fp_line
			(start -1.1049 0.724916)
			(end -1.1049 -0.724916)
			(stroke
				(width 0.1)
				(type default)
			)
			(layer "B.Fab")
		)
		(fp_line
			(start 1.1049 -0.724916)
			(end 1.1049 0.724916)
			(stroke
				(width 0.1)
				(type default)
			)
			(layer "B.Fab")
		)
		(fp_line
			(start 1.1049 0.724916)
			(end -1.1049 0.724916)
			(stroke
				(width 0.1)
				(type default)
			)
			(layer "B.Fab")
		)
		(pad "1" smd rect
			(at 0.889 0)
			(size 1.016 1.27)
			(layers "B.Cu" "B.Mask" "B.Paste")
			(net "SW_P12V_AUX_PVDDIO_P1_FLT")
		)
		(pad "2" smd rect
			(at -0.889 0)
			(size 1.016 1.27)
			(layers "B.Cu" "B.Mask" "B.Paste")
			(net "GND")
		)
	)
)
